# S9S_MB_2U (Grand Teton) — schematic netlist excerpt (pin names and nets, part order shuffled) for the footprints in the layout excerpt that follows; sources: Cadence DE-HDL packaged netlist, KiCad conversion of 03242023_DA0F0TMBIJ0_F0T_Motherboard_J_brd_V01_OCP.brd

Q119  MOSFET_NCH_DUAL  PJT138K IC  pkg SOT363XD  page 162
  S1  = GND
  G1  = P3V3_OCP_EN_2_R
  D2  = P3V3_OCP_UV_2_R1
  S2  = GND
  G2  = P3V3_OCP_2_EN_G
  D1  = P3V3_OCP_2_EN_G

R3474  Q_RES  4.7K 5% CHIP  pkg 0402LF  page 147 : A = P3V3_AUX ; B = GPU_PRSNT

(kicad_pcb
	(version 20260206)
	(generator "pcbnew")
	(generator_version "10.0")
	(general
		(thickness 1.6)
		(legacy_teardrops no)
	)
	(paper "A4")
	(title_block
		(title "03242023_DA0F0TMBIJ0_F0T_Motherboard_J_brd_V01_OCP.brd")
		(comment 1 "Grand Teton / footprints 2242-2243 of 6105")
	)
	(layers
		(0 "F.Cu" signal "TOP")
		(4 "In1.Cu" signal "GND")
		(6 "In2.Cu" signal "IN1")
		(8 "In3.Cu" signal "GND1")
		(10 "In4.Cu" signal "IN2")
		(12 "In5.Cu" signal "GND2")
		(14 "In6.Cu" signal "IN3")
		(16 "In7.Cu" signal "GND3")
		(18 "In8.Cu" signal "VCC")
		(20 "In9.Cu" signal "VCC1")
		(22 "In10.Cu" signal "GND4")
		(24 "In11.Cu" signal "IN4")
		(26 "In12.Cu" signal "GND5")
		(28 "In13.Cu" signal "IN5")
		(30 "In14.Cu" signal "GND6")
		(32 "In15.Cu" signal "IN6")
		(34 "In16.Cu" signal "GND7")
		(2 "B.Cu" signal "BOTTOM")
		(9 "F.Adhes" user "F.Adhesive")
		(11 "B.Adhes" user "B.Adhesive")
		(13 "F.Paste" user "Package Geometry/Pastemask Top")
		(15 "B.Paste" user "Package Geometry/Pastemask Bottom")
		(5 "F.SilkS" user "Ref Des/Silkscreen Top")
		(7 "B.SilkS" user "Ref Des/Silkscreen Bottom")
		(1 "F.Mask" user "Board Geometry/Soldermask Top")
		(3 "B.Mask" user "Board Geometry/Soldermask Bottom")
		(17 "Dwgs.User" user "User.Drawings")
		(19 "Cmts.User" user "User.Comments")
		(21 "Eco1.User" user "User.Eco1")
		(23 "Eco2.User" user "User.Eco2")
		(25 "Edge.Cuts" user "Board Geometry/Outline")
		(27 "Margin" user)
		(31 "F.CrtYd" user "Package Geometry/Place Bound Top")
		(29 "B.CrtYd" user "Package Geometry/Place Bound Bottom")
		(35 "F.Fab" user "Ref Des/Assembly Top")
		(33 "B.Fab" user "Ref Des/Assembly Bottom")
	)
	(footprint ""
		(layer "F.Cu")
		(at 62.48273 -40.031162)
		(property "Reference" "Q119"
			(at -0.89789 -2.121916 0)
			(unlocked yes)
			(layer "F.SilkS")
			(effects
				(font
					(size 0.7874 0.5842)
					(thickness 0.1524)
				)
				(justify left)
			)
		)
		(property "Value" ""
			(at 0 0 0)
			(layer "F.Fab")
			(effects
				(font
					(size 1.27 1.27)
				)
			)
		)
		(duplicate_pad_numbers_are_jumpers no)
		(fp_line
			(start -1.332738 -1.100074)
			(end -0.4826 -1.100074)
			(stroke
				(width 0.1524)
				(type default)
			)
			(layer "F.SilkS")
		)
		(fp_line
			(start -1.332738 1.100074)
			(end -1.332738 -1.100074)
			(stroke
				(width 0.1524)
				(type default)
			)
			(layer "F.SilkS")
		)
		(fp_line
			(start -0.4826 -1.100074)
			(end 0 -0.541274)
			(stroke
				(width 0.1524)
				(type default)
			)
			(layer "F.SilkS")
		)
		(fp_line
			(start 0 -0.541274)
			(end 0.4826 -1.100074)
			(stroke
				(width 0.1524)
				(type default)
			)
			(layer "F.SilkS")
		)
		(fp_line
			(start 0.4826 -1.100074)
			(end 1.332738 -1.100074)
			(stroke
				(width 0.1524)
				(type default)
			)
			(layer "F.SilkS")
		)
		(fp_line
			(start 1.332738 -1.100074)
			(end 1.332738 1.100074)
			(stroke
				(width 0.1524)
				(type default)
			)
			(layer "F.SilkS")
		)
		(fp_line
			(start 1.332738 1.100074)
			(end -1.332738 1.100074)
			(stroke
				(width 0.1524)
				(type default)
			)
			(layer "F.SilkS")
		)
		(fp_poly
			(pts
				(xy -2.2352 -1.001014) (xy -1.533144 -0.649986) (xy -2.2352 -0.298958)
			)
			(stroke
				(width 0)
				(type default)
			)
			(fill yes)
			(layer "F.SilkS")
		)
		(fp_line
			(start -0.674878 -1.100074)
			(end 0.674878 -1.100074)
			(stroke
				(width 0.1)
				(type default)
			)
			(layer "F.Fab")
		)
		(fp_line
			(start -0.674878 1.100074)
			(end -0.674878 -1.100074)
			(stroke
				(width 0.1)
				(type default)
			)
			(layer "F.Fab")
		)
		(fp_line
			(start 0.674878 -1.100074)
			(end 0.674878 1.100074)
			(stroke
				(width 0.1)
				(type default)
			)
			(layer "F.Fab")
		)
		(fp_line
			(start 0.674878 1.100074)
			(end -0.674878 1.100074)
			(stroke
				(width 0.1)
				(type default)
			)
			(layer "F.Fab")
		)
		(fp_poly
			(pts
				(xy -2.2352 -0.298958) (xy -2.2352 -1.001014) (xy -1.533144 -0.649986)
			)
			(stroke
				(width 0)
				(type default)
			)
			(fill yes)
			(layer "F.Fab")
		)
		(pad "1" smd rect
			(at -0.94996 -0.649986 90)
			(size 0.4318 0.508)
			(layers "F.Cu" "F.Mask" "F.Paste")
			(net "GND")
		)
		(pad "2" smd rect
			(at -0.94996 0 90)
			(size 0.4318 0.508)
			(layers "F.Cu" "F.Mask" "F.Paste")
			(net "P3V3_OCP_EN_2_R")
		)
		(pad "3" smd rect
			(at -0.94996 0.649986 90)
			(size 0.4318 0.508)
			(layers "F.Cu" "F.Mask" "F.Paste")
			(net "P3V3_OCP_UV_2_R1")
		)
		(pad "4" smd rect
			(at 0.94996 0.649986 90)
			(size 0.4318 0.508)
			(layers "F.Cu" "F.Mask" "F.Paste")
			(net "GND")
		)
		(pad "5" smd rect
			(at 0.94996 0 90)
			(size 0.4318 0.508)
			(layers "F.Cu" "F.Mask" "F.Paste")
			(net "P3V3_OCP_2_EN_G")
		)
		(pad "6" smd rect
			(at 0.94996 -0.649986 90)
			(size 0.4318 0.508)
			(layers "F.Cu" "F.Mask" "F.Paste")
			(net "P3V3_OCP_2_EN_G")
		)
	)
	(footprint ""
		(layer "F.Cu")
		(at 32.145732 -412.069534 180)
		(property "Reference" "R3474"
			(at 0 0 180)
			(layer "F.SilkS")
			(hide yes)
			(effects
				(font
					(size 1.27 1.27)
				)
			)
		)
		(property "Value" ""
			(at 0 0 180)
			(layer "F.Fab")
			(effects
				(font
					(size 1.27 1.27)
				)
			)
		)
		(duplicate_pad_numbers_are_jumpers no)
		(fp_line
			(start 0.7874 0.4064)
			(end -0.7874 0.4064)
			(stroke
				(width 0.1524)
				(type default)
			)
			(layer "F.SilkS")
		)
		(fp_line
			(start 0.7874 -0.4064)
			(end 0.7874 0.4064)
			(stroke
				(width 0.1524)
				(type default)
			)
			(layer "F.SilkS")
		)
		(fp_line
			(start -0.7874 0.4064)
			(end -0.7874 -0.4064)
			(stroke
				(width 0.1524)
				(type default)
			)
			(layer "F.SilkS")
		)
		(fp_line
			(start -0.7874 -0.4064)
			(end 0.7874 -0.4064)
			(stroke
				(width 0.1524)
				(type default)
			)
			(layer "F.SilkS")
		)
		(fp_line
			(start 0.67945 0.3048)
			(end 0.120396 0.3048)
			(stroke
				(width 0.1)
				(type default)
			)
			(layer "F.Fab")
		)
		(fp_line
			(start 0.67945 -0.3048)
			(end 0.67945 0.3048)
			(stroke
				(width 0.1)
				(type default)
			)
			(layer "F.Fab")
		)
		(fp_line
			(start 0.12065 -0.2794)
			(end 0.12065 -0.3048)
			(stroke
				(width 0.1)
				(type default)
			)
			(layer "F.Fab")
		)
		(fp_line
			(start 0.12065 -0.3048)
			(end 0.67945 -0.3048)
			(stroke
				(width 0.1)
				(type default)
			)
			(layer "F.Fab")
		)
		(fp_line
			(start 0.120396 0.3048)
			(end 0.120396 0.2794)
			(stroke
				(width 0.1)
				(type default)
			)
			(layer "F.Fab")
		)
		(fp_line
			(start 0.120396 0.2794)
			(end -0.12065 0.2794)
			(stroke
				(width 0.1)
				(type default)
			)
			(layer "F.Fab")
		)
		(fp_line
			(start -0.12065 0.3048)
			(end -0.67945 0.3048)
			(stroke
				(width 0.1)
				(type default)
			)
			(layer "F.Fab")
		)
		(fp_line
			(start -0.12065 0.2794)
			(end -0.12065 0.3048)
			(stroke
				(width 0.1)
				(type default)
			)
			(layer "F.Fab")
		)
		(fp_line
			(start -0.12065 -0.2794)
			(end 0.12065 -0.2794)
			(stroke
				(width 0.1)
				(type default)
			)
			(layer "F.Fab")
		)
		(fp_line
			(start -0.12065 -0.305054)
			(end -0.12065 -0.2794)
			(stroke
				(width 0.1)
				(type default)
			)
			(layer "F.Fab")
		)
		(fp_line
			(start -0.67945 0.3048)
			(end -0.67945 -0.305054)
			(stroke
				(width 0.1)
				(type default)
			)
			(layer "F.Fab")
		)
		(fp_line
			(start -0.67945 -0.305054)
			(end -0.12065 -0.305054)
			(stroke
				(width 0.1)
				(type default)
			)
			(layer "F.Fab")
		)
		(pad "1" smd circle
			(at -0.40005 0 180)
			(size 0 0)
			(layers "F.Cu" "F.Mask" "F.Paste")
			(net "P3V3_AUX")
		)
		(pad "2" smd circle
			(at 0.40005 0 180)
			(size 0 0)
			(layers "F.Cu" "F.Mask" "F.Paste")
			(net "GPU_PRSNT")
		)
	)
)
